(kicad_pcb
	(version 20260206)
	(generator "pcbnew")
	(generator_version "10.0")
	(general
		(thickness 1.6)
		(legacy_teardrops no)
	)
	(paper "A4")
	(title_block
		(title "pdpb — Lightning_PDPB_BRD.brd")
		(comment 1 "Lightning (Wiwynn / Facebook NVMe JBOF) / footprints 268-268 of 1140")
	)
	(layers
		(0 "F.Cu" signal "TOP")
		(4 "In1.Cu" signal "L2GND")
		(6 "In2.Cu" signal "L3")
		(8 "In3.Cu" signal "L4VCC")
		(10 "In4.Cu" signal "L5VCC")
		(12 "In5.Cu" signal "L6")
		(14 "In6.Cu" signal "L7GND")
		(2 "B.Cu" signal "BOTTOM")
		(9 "F.Adhes" user "F.Adhesive")
		(11 "B.Adhes" user "B.Adhesive")
		(13 "F.Paste" user "Package Geometry/Pastemask Top")
		(15 "B.Paste" user "Package Geometry/Pastemask Bottom")
		(5 "F.SilkS" user "Ref Des/Silkscreen Top")
		(7 "B.SilkS" user "Ref Des/Silkscreen Bottom")
		(1 "F.Mask" user "Board Geometry/Soldermask Top")
		(3 "B.Mask" user "Board Geometry/Soldermask Bottom")
		(17 "Dwgs.User" user "User.Drawings")
		(19 "Cmts.User" user "User.Comments")
		(21 "Eco1.User" user "User.Eco1")
		(23 "Eco2.User" user "User.Eco2")
		(25 "Edge.Cuts" user "Board Geometry/Outline")
		(27 "Margin" user)
		(31 "F.CrtYd" user "Package Geometry/Place Bound Top")
		(29 "B.CrtYd" user "Package Geometry/Place Bound Bottom")
		(35 "F.Fab" user "Ref Des/Assembly Top")
		(33 "B.Fab" user "Ref Des/Assembly Bottom")
	)
	(footprint ""
		(layer "F.Cu")
		(at 41.150032 -170.669966 90)
		(property "Reference" "J8"
			(at 0 0 90)
			(layer "F.SilkS")
			(hide yes)
			(effects
				(font
					(size 1.27 1.27)
				)
			)
		)
		(property "Value" "PCISLT68-14-GP-U1"
			(at -22.225 12.7508 90)
			(unlocked yes)
			(layer "F.Fab")
			(hide yes)
			(effects
				(font
					(size 1.016 1.016)
					(thickness 0.1524)
				)
			)
		)
		(property "Device Type" "SD-78827-0001"
			(at -22.225 11.2268 90)
			(unlocked yes)
			(layer "F.Fab")
			(hide yes)
			(effects
				(font
					(size 1.016 1.016)
					(thickness 0.1524)
				)
			)
		)
		(duplicate_pad_numbers_are_jumpers no)
		(fp_line
			(start 20.4724 -3.4036)
			(end 20.4724 0.0254)
			(stroke
				(width 0.1524)
				(type default)
			)
			(layer "F.SilkS")
		)
		(fp_line
			(start -20.4724 -3.4036)
			(end 20.4724 -3.4036)
			(stroke
				(width 0.1524)
				(type default)
			)
			(layer "F.SilkS")
		)
		(fp_line
			(start 23.749 0.0254)
			(end 23.749 4.6736)
			(stroke
				(width 0.1524)
				(type default)
			)
			(layer "F.SilkS")
		)
		(fp_line
			(start 20.4724 0.0254)
			(end 23.749 0.0254)
			(stroke
				(width 0.1524)
				(type default)
			)
			(layer "F.SilkS")
		)
		(fp_line
			(start -20.4724 0.0254)
			(end -20.4724 -3.4036)
			(stroke
				(width 0.1524)
				(type default)
			)
			(layer "F.SilkS")
		)
		(fp_line
			(start -23.749 0.0254)
			(end -20.4724 0.0254)
			(stroke
				(width 0.1524)
				(type default)
			)
			(layer "F.SilkS")
		)
		(fp_line
			(start 23.117556 1.803908)
			(end 23.117556 2.896108)
			(stroke
				(width 0.3048)
				(type default)
			)
			(layer "F.SilkS")
		)
		(fp_line
			(start -20.882356 1.803908)
			(end -20.882356 2.896108)
			(stroke
				(width 0.3048)
				(type default)
			)
			(layer "F.SilkS")
		)
		(fp_line
			(start 20.882356 2.896108)
			(end 20.882356 1.803908)
			(stroke
				(width 0.3048)
				(type default)
			)
			(layer "F.SilkS")
		)
		(fp_line
			(start -23.117556 2.896108)
			(end -23.117556 1.803908)
			(stroke
				(width 0.3048)
				(type default)
			)
			(layer "F.SilkS")
		)
		(fp_line
			(start 23.749 4.6736)
			(end 20.4724 4.6736)
			(stroke
				(width 0.1524)
				(type default)
			)
			(layer "F.SilkS")
		)
		(fp_line
			(start 20.4724 4.6736)
			(end 20.4724 12.0142)
			(stroke
				(width 0.1524)
				(type default)
			)
			(layer "F.SilkS")
		)
		(fp_line
			(start -20.4724 4.6736)
			(end -23.749 4.6736)
			(stroke
				(width 0.1524)
				(type default)
			)
			(layer "F.SilkS")
		)
		(fp_line
			(start -23.749 4.6736)
			(end -23.749 0.0254)
			(stroke
				(width 0.1524)
				(type default)
			)
			(layer "F.SilkS")
		)
		(fp_line
			(start 17.8435 10.3124)
			(end -17.8435 10.3124)
			(stroke
				(width 0.1524)
				(type default)
			)
			(layer "F.SilkS")
		)
		(fp_line
			(start -17.8435 10.3124)
			(end -17.8435 12.0142)
			(stroke
				(width 0.1524)
				(type default)
			)
			(layer "F.SilkS")
		)
		(fp_line
			(start 20.4724 12.0142)
			(end 17.8435 12.0142)
			(stroke
				(width 0.1524)
				(type default)
			)
			(layer "F.SilkS")
		)
		(fp_line
			(start 17.8435 12.0142)
			(end 17.8435 10.3124)
			(stroke
				(width 0.1524)
				(type default)
			)
			(layer "F.SilkS")
		)
		(fp_line
			(start -17.8435 12.0142)
			(end -20.4724 12.0142)
			(stroke
				(width 0.1524)
				(type default)
			)
			(layer "F.SilkS")
		)
		(fp_line
			(start -20.4724 12.0142)
			(end -20.4724 4.6736)
			(stroke
				(width 0.1524)
				(type default)
			)
			(layer "F.SilkS")
		)
		(fp_arc
			(start 20.882356 1.803908)
			(mid 21.999956 0.686308)
			(end 23.117556 1.803908)
			(stroke
				(width 0.3048)
				(type default)
			)
			(layer "F.SilkS")
		)
		(fp_arc
			(start -23.117556 1.803908)
			(mid -21.999956 0.686308)
			(end -20.882356 1.803908)
			(stroke
				(width 0.3048)
				(type default)
			)
			(layer "F.SilkS")
		)
		(fp_arc
			(start 23.117556 2.896108)
			(mid 21.999956 4.013708)
			(end 20.882356 2.896108)
			(stroke
				(width 0.3048)
				(type default)
			)
			(layer "F.SilkS")
		)
		(fp_arc
			(start -20.882356 2.896108)
			(mid -21.999956 4.013708)
			(end -23.117556 2.896108)
			(stroke
				(width 0.3048)
				(type default)
			)
			(layer "F.SilkS")
		)
		(fp_poly
			(pts
				(xy -20.2184 11.7602) (xy -20.2184 4.4196) (xy -23.495 4.4196) (xy -23.495 0.2794) (xy -20.2184 0.2794)
				(xy -20.2184 -3.1496) (xy 20.2184 -3.1496) (xy 20.2184 0.2794) (xy 23.495 0.2794) (xy 23.495 4.4196)
				(xy 20.2184 4.4196) (xy 20.2184 11.7602) (xy 18.0975 11.7602) (xy 18.0975 10.0584) (xy -18.0975 10.0584)
				(xy -18.0975 11.7602)
			)
			(stroke
				(width 0)
				(type default)
			)
			(fill no)
			(layer "F.CrtYd")
		)
		(fp_poly
			(pts
				(xy -21.2471 16.256) (xy -21.2471 4.9276) (xy -24.003 4.9276) (xy -24.003 -0.2286) (xy -20.7264 -0.2286)
				(xy -20.7264 -3.6576) (xy 20.7264 -3.6576) (xy 20.7264 -0.2286) (xy 24.003 -0.2286) (xy 24.003 -0.00635)
				(xy 20.2184 -0.00635) (xy 20.2184 -3.1496) (xy -20.2184 -3.1496) (xy -20.2184 0.2794) (xy -23.495 0.2794)
				(xy -23.495 4.4196) (xy -20.2184 4.4196) (xy -20.2184 11.7602) (xy -18.0975 11.7602) (xy -18.0975 10.0584)
				(xy 18.0975 10.0584) (xy 18.0975 11.7602) (xy 20.2184 11.7602) (xy 20.2184 4.4196) (xy 23.495 4.4196)
				(xy 23.495 0.2794) (xy 20.2184 0.2794) (xy 20.2184 0.00635) (xy 24.003 0.00635) (xy 24.003 4.9276)
				(xy 21.2471 4.9276) (xy 21.2471 16.256)
			)
			(stroke
				(width 0)
				(type default)
			)
			(fill no)
			(layer "F.CrtYd")
		)
		(fp_poly
			(pts
				(xy -21.2471 16.256) (xy -21.2471 4.9276) (xy -24.003 4.9276) (xy -24.003 -0.2286) (xy -20.7264 -0.2286)
				(xy -20.7264 -3.6576) (xy 20.7264 -3.6576) (xy 20.7264 -0.2286) (xy 24.003 -0.2286) (xy 24.003 4.9276)
				(xy 21.2471 4.9276) (xy 21.2471 16.256)
			)
			(stroke
				(width 0)
				(type default)
			)
			(fill no)
			(layer "F.Fab")
		)
		(pad "" np_thru_hole circle
			(at -18.999962 0 90)
			(size 0.254 0.254)
			(drill 1.8542)
			(layers "*.Cu" "*.Mask")
			(clearance 1.1557)
			(thermal_gap 1.1557)
		)
		(pad "" np_thru_hole circle
			(at 18.999962 0 90)
			(size 0.254 0.254)
			(drill 1.8542)
			(layers "*.Cu" "*.Mask")
			(clearance 1.1557)
			(thermal_gap 1.1557)
		)
		(pad "E1" smd rect
			(at -7.079996 1.240028 90)
			(size 0.508 2.0066)
			(layers "F.Cu" "F.Mask" "F.Paste")
			(net "PE_CLK100M_DR8_2_P")
		)
		(pad "E2" smd rect
			(at -6.279896 1.240028 90)
			(size 0.508 2.0066)
			(layers "F.Cu" "F.Mask" "F.Paste")
			(net "PE_CLK100M_DR8_2_N")
		)
		(pad "E3" smd rect
			(at -5.48005 1.240028 90)
			(size 0.508 2.0066)
			(layers "F.Cu" "F.Mask" "F.Paste")
			(net "P3V3")
		)
		(pad "E4" smd rect
			(at -4.67995 1.240028 90)
			(size 0.508 2.0066)
			(layers "F.Cu" "F.Mask" "F.Paste")
			(net "SSD8_PERST_N")
		)
		(pad "E5" smd rect
			(at -3.880104 1.240028 90)
			(size 0.508 2.0066)
			(layers "F.Cu" "F.Mask" "F.Paste")
			(net "SSD8_PERST_N")
		)
		(pad "E6" smd rect
			(at -3.080004 1.240028 90)
			(size 0.508 2.0066)
			(layers "F.Cu" "F.Mask" "F.Paste")
			(net "Net_1089")
		)
		(pad "E7" smd rect
			(at -15.48003 -1.949958 90)
			(size 0.508 2.0066)
			(layers "F.Cu" "F.Mask" "F.Paste")
			(net "PE_CLK100M_DR8_1_P")
		)
		(pad "E8" smd rect
			(at -14.67993 -1.949958 90)
			(size 0.508 2.0066)
			(layers "F.Cu" "F.Mask" "F.Paste")
			(net "PE_CLK100M_DR8_1_N")
		)
		(pad "E9" smd rect
			(at -13.880084 -1.949958 90)
			(size 0.508 2.0066)
			(layers "F.Cu" "F.Mask" "F.Paste")
			(net "GND")
		)
		(pad "E10" smd rect
			(at -13.079984 -1.949958 90)
			(size 0.508 2.0066)
			(layers "F.Cu" "F.Mask" "F.Paste")
			(net "PE_TX1_DR8_N")
		)
		(pad "E11" smd rect
			(at -12.279884 -1.949958 90)
			(size 0.508 2.0066)
			(layers "F.Cu" "F.Mask" "F.Paste")
			(net "PE_TX1_DR8_P")
		)
		(pad "E12" smd rect
			(at -11.480038 -1.949958 90)
			(size 0.508 2.0066)
			(layers "F.Cu" "F.Mask" "F.Paste")
			(net "GND")
		)
		(pad "E13" smd rect
			(at -10.679938 -1.949958 90)
			(size 0.508 2.0066)
			(layers "F.Cu" "F.Mask" "F.Paste")
			(net "PE_RX1_DR8_N")
		)
		(pad "E14" smd rect
			(at -9.880092 -1.949958 90)
			(size 0.508 2.0066)
			(layers "F.Cu" "F.Mask" "F.Paste")
			(net "PE_RX1_DR8_P")
		)
		(pad "E15" smd rect
			(at -9.079992 -1.949958 90)
			(size 0.508 2.0066)
			(layers "F.Cu" "F.Mask" "F.Paste")
			(net "GND")
		)
		(pad "E16" smd rect
			(at -8.279892 -1.949958 90)
			(size 0.508 2.0066)
			(layers "F.Cu" "F.Mask" "F.Paste")
			(net "Net_1096")
		)
		(pad "E17" smd rect
			(at 9.320022 -1.949958 90)
			(size 0.508 2.0066)
			(layers "F.Cu" "F.Mask" "F.Paste")
			(net "PE_TX4_DR8_N")
		)
		(pad "E18" smd rect
			(at 10.120122 -1.949958 90)
			(size 0.508 2.0066)
			(layers "F.Cu" "F.Mask" "F.Paste")
			(net "PE_TX4_DR8_P")
		)
		(pad "E19" smd rect
			(at 10.919968 -1.949958 90)
			(size 0.508 2.0066)
			(layers "F.Cu" "F.Mask" "F.Paste")
			(net "GND")
		)
		(pad "E20" smd rect
			(at 11.720068 -1.949958 90)
			(size 0.508 2.0066)
			(layers "F.Cu" "F.Mask" "F.Paste")
			(net "PE_RX4_DR8_N")
		)
		(pad "E21" smd rect
			(at 12.519914 -1.949958 90)
			(size 0.508 2.0066)
			(layers "F.Cu" "F.Mask" "F.Paste")
			(net "PE_RX4_DR8_P")
		)
		(pad "E22" smd rect
			(at 13.320014 -1.949958 90)
			(size 0.508 2.0066)
			(layers "F.Cu" "F.Mask" "F.Paste")
			(net "GND")
		)
		(pad "E23" smd rect
			(at 14.120114 -1.949958 90)
			(size 0.508 2.0066)
			(layers "F.Cu" "F.Mask" "F.Paste")
			(net "SCL_DR8_R")
		)
		(pad "E24" smd rect
			(at 14.91996 -1.949958 90)
			(size 0.508 2.0066)
			(layers "F.Cu" "F.Mask" "F.Paste")
			(net "SDA_DR8_R")
		)
		(pad "E25" smd rect
			(at 15.72006 -1.949958 90)
			(size 0.508 2.0066)
			(layers "F.Cu" "F.Mask" "F.Paste")
			(net "DUALPORTEN#8")
		)
		(pad "P1" smd rect
			(at -1.905 0.824992 90)
			(size 0.6604 2.0574)
			(layers "F.Cu" "F.Mask" "F.Paste")
			(net "Net_1092")
		)
		(pad "P2" smd rect
			(at -0.635 0.824992 90)
			(size 0.6604 2.0574)
			(layers "F.Cu" "F.Mask" "F.Paste")
			(net "Net_1091")
		)
		(pad "P3" smd rect
			(at 0.635 0.824992 90)
			(size 0.6604 2.0574)
			(layers "F.Cu" "F.Mask" "F.Paste")
			(net "Net_1090")
		)
		(pad "P4" smd rect
			(at 1.905 0.824992 90)
			(size 0.6604 2.0574)
			(layers "F.Cu" "F.Mask" "F.Paste")
			(net "SSD8_CLK0_OE_N")
		)
		(pad "P5" smd rect
			(at 3.175 0.824992 90)
			(size 0.6604 2.0574)
			(layers "F.Cu" "F.Mask" "F.Paste")
			(net "GND")
		)
		(pad "P6" smd rect
			(at 4.445 0.824992 90)
			(size 0.6604 2.0574)
			(layers "F.Cu" "F.Mask" "F.Paste")
			(net "GND")
		)
		(pad "P7" smd rect
			(at 5.715 0.824992 90)
			(size 0.6604 2.0574)
			(layers "F.Cu" "F.Mask" "F.Paste")
			(net "Net_97")
		)
		(pad "P8" smd rect
			(at 6.985 0.824992 90)
			(size 0.6604 2.0574)
			(layers "F.Cu" "F.Mask" "F.Paste")
			(net "Net_69")
		)
		(pad "P9" smd rect
			(at 8.255 0.824992 90)
			(size 0.6604 2.0574)
			(layers "F.Cu" "F.Mask" "F.Paste")
			(net "Net_83")
		)
		(pad "P10" smd rect
			(at 9.525 0.824992 90)
			(size 0.6604 2.0574)
			(layers "F.Cu" "F.Mask" "F.Paste")
			(net "SSD_PRSNT_NET8")
		)
		(pad "P11" smd rect
			(at 10.795 0.824992 90)
			(size 0.6604 2.0574)
			(layers "F.Cu" "F.Mask" "F.Paste")
			(net "SSD_ACT_DR8")
		)
		(pad "P12" smd rect
			(at 12.065 0.824992 90)
			(size 0.6604 2.0574)
			(layers "F.Cu" "F.Mask" "F.Paste")
			(net "GND")
		)
		(pad "P13" smd rect
			(at 13.335 0.824992 90)
			(size 0.6604 2.0574)
			(layers "F.Cu" "F.Mask" "F.Paste")
			(net "12V_PRECH_SSD8")
		)
		(pad "P14" smd rect
			(at 14.605 0.824992 90)
			(size 0.6604 2.0574)
			(layers "F.Cu" "F.Mask" "F.Paste")
			(net "P12V_SSD8")
		)
		(pad "P15" smd rect
			(at 15.875 0.824992 90)
			(size 0.6604 2.0574)
			(layers "F.Cu" "F.Mask" "F.Paste")
			(net "P12V_SSD8")
		)
		(pad "PTH1" thru_hole oval
			(at -21.999956 2.350008 90)
			(size 1.524 2.6162)
			(drill oval 0.8128 1.905)
			(layers "*.Cu" "*.Mask")
			(remove_unused_layers no)
			(net "Net_1101")
			(clearance 0.1524)
			(thermal_gap 0.1524)
		)
		(pad "PTH2" thru_hole oval
			(at 21.999956 2.350008 90)
			(size 1.524 2.6162)
			(drill oval 0.8128 1.905)
			(layers "*.Cu" "*.Mask")
			(remove_unused_layers no)
			(net "Net_1085")
			(clearance 0.1524)
			(thermal_gap 0.1524)
		)
		(pad "S1" smd rect
			(at -15.875 0.824992 90)
			(size 0.6604 2.0574)
			(layers "F.Cu" "F.Mask" "F.Paste")
			(net "GND")
		)
		(pad "S2" smd rect
			(at -14.605 0.824992 90)
			(size 0.6604 2.0574)
			(layers "F.Cu" "F.Mask" "F.Paste")
			(net "Net_1100")
		)
		(pad "S3" smd rect
			(at -13.335 0.824992 90)
			(size 0.6604 2.0574)
			(layers "F.Cu" "F.Mask" "F.Paste")
			(net "Net_1099")
		)
		(pad "S4" smd rect
			(at -12.065 0.824992 90)
			(size 0.6604 2.0574)
			(layers "F.Cu" "F.Mask" "F.Paste")
			(net "GND")
		)
		(pad "S5" smd rect
			(at -10.795 0.824992 90)
			(size 0.6604 2.0574)
			(layers "F.Cu" "F.Mask" "F.Paste")
			(net "Net_1098")
		)
		(pad "S6" smd rect
			(at -9.525 0.824992 90)
			(size 0.6604 2.0574)
			(layers "F.Cu" "F.Mask" "F.Paste")
			(net "Net_1097")
		)
		(pad "S7" smd rect
			(at -8.255 0.824992 90)
			(size 0.6604 2.0574)
			(layers "F.Cu" "F.Mask" "F.Paste")
			(net "GND")
		)
		(pad "S8" smd rect
			(at -7.480046 -1.949958 90)
			(size 0.508 2.0066)
			(layers "F.Cu" "F.Mask" "F.Paste")
			(net "GND")
		)
		(pad "S9" smd rect
			(at -6.679946 -1.949958 90)
			(size 0.508 2.0066)
			(layers "F.Cu" "F.Mask" "F.Paste")
			(net "Net_1095")
		)
		(pad "S10" smd rect
			(at -5.8801 -1.949958 90)
			(size 0.508 2.0066)
			(layers "F.Cu" "F.Mask" "F.Paste")
			(net "Net_1094")
		)
		(pad "S11" smd rect
			(at -5.08 -1.949958 90)
			(size 0.508 2.0066)
			(layers "F.Cu" "F.Mask" "F.Paste")
			(net "GND")
		)
		(pad "S12" smd rect
			(at -4.2799 -1.949958 90)
			(size 0.508 2.0066)
			(layers "F.Cu" "F.Mask" "F.Paste")
			(net "Net_1093")
		)
		(pad "S13" smd rect
			(at -3.480054 -1.949958 90)
			(size 0.508 2.0066)
			(layers "F.Cu" "F.Mask" "F.Paste")
			(net "Net_1088")
		)
		(pad "S14" smd rect
			(at -2.679954 -1.949958 90)
			(size 0.508 2.0066)
			(layers "F.Cu" "F.Mask" "F.Paste")
			(net "GND")
		)
		(pad "S15" smd rect
			(at -1.880108 -1.949958 90)
			(size 0.508 2.0066)
			(layers "F.Cu" "F.Mask" "F.Paste")
			(net "Net_1087")
		)
		(pad "S16" smd rect
			(at -1.080008 -1.949958 90)
			(size 0.508 2.0066)
			(layers "F.Cu" "F.Mask" "F.Paste")
			(net "GND")
		)
		(pad "S17" smd rect
			(at -0.279908 -1.949958 90)
			(size 0.508 2.0066)
			(layers "F.Cu" "F.Mask" "F.Paste")
			(net "PE_TX2_DR8_N")
		)
		(pad "S18" smd rect
			(at 0.519938 -1.949958 90)
			(size 0.508 2.0066)
			(layers "F.Cu" "F.Mask" "F.Paste")
			(net "PE_TX2_DR8_P")
		)
		(pad "S19" smd rect
			(at 1.320038 -1.949958 90)
			(size 0.508 2.0066)
			(layers "F.Cu" "F.Mask" "F.Paste")
			(net "GND")
		)
		(pad "S20" smd rect
			(at 2.119884 -1.949958 90)
			(size 0.508 2.0066)
			(layers "F.Cu" "F.Mask" "F.Paste")
			(net "PE_RX2_DR8_N")
		)
		(pad "S21" smd rect
			(at 2.919984 -1.949958 90)
			(size 0.508 2.0066)
			(layers "F.Cu" "F.Mask" "F.Paste")
			(net "PE_RX2_DR8_P")
		)
		(pad "S22" smd rect
			(at 3.720084 -1.949958 90)
			(size 0.508 2.0066)
			(layers "F.Cu" "F.Mask" "F.Paste")
			(net "GND")
		)
		(pad "S23" smd rect
			(at 4.51993 -1.949958 90)
			(size 0.508 2.0066)
			(layers "F.Cu" "F.Mask" "F.Paste")
			(net "PE_TX3_DR8_N")
		)
		(pad "S24" smd rect
			(at 5.32003 -1.949958 90)
			(size 0.508 2.0066)
			(layers "F.Cu" "F.Mask" "F.Paste")
			(net "PE_TX3_DR8_P")
		)
		(pad "S25" smd rect
			(at 6.119876 -1.949958 90)
			(size 0.508 2.0066)
			(layers "F.Cu" "F.Mask" "F.Paste")
			(net "GND")
		)
		(pad "S26" smd rect
			(at 6.919976 -1.949958 90)
			(size 0.508 2.0066)
			(layers "F.Cu" "F.Mask" "F.Paste")
			(net "PE_RX3_DR8_N")
		)
		(pad "S27" smd rect
			(at 7.720076 -1.949958 90)
			(size 0.508 2.0066)
			(layers "F.Cu" "F.Mask" "F.Paste")
			(net "PE_RX3_DR8_P")
		)
		(pad "S28" smd rect
			(at 8.519922 -1.949958 90)
			(size 0.508 2.0066)
			(layers "F.Cu" "F.Mask" "F.Paste")
			(net "GND")
		)
		(zone
			(layers "F.Cu" "B.Cu" "In1.Cu" "In2.Cu" "In3.Cu" "In4.Cu" "In5.Cu" "In6.Cu")
			(hatch none 0.5)
			(connect_pads
				(clearance 0)
			)
			(min_thickness 0.25)
			(keepout
				(tracks not_allowed)
				(vias allowed)
				(pads allowed)
				(copperpour not_allowed)
				(footprints allowed)
			)
			(placement
				(enabled no)
				(sheetname "")
			)
			(fill
				(thermal_gap 0.5)
				(thermal_bridge_width 0.5)
				(island_removal_mode 0)
			)
			(polygon
				(pts
					(arc
						(start 42.381932 -189.669928)
						(mid 39.918132 -189.669928)
						(end 42.381932 -189.669928)
					)
				)
			)
		)
		(zone
			(layers "F.Cu" "B.Cu" "In1.Cu" "In2.Cu" "In3.Cu" "In4.Cu" "In5.Cu" "In6.Cu")
			(hatch none 0.5)
			(connect_pads
				(clearance 0)
			)
			(min_thickness 0.25)
			(keepout
				(tracks not_allowed)
				(vias allowed)
				(pads allowed)
				(copperpour not_allowed)
				(footprints allowed)
			)
			(placement
				(enabled no)
				(sheetname "")
			)
			(fill
				(thermal_gap 0.5)
				(thermal_bridge_width 0.5)
				(island_removal_mode 0)
			)
			(polygon
				(pts
					(arc
						(start 42.381932 -151.670004)
						(mid 39.918132 -151.670004)
						(end 42.381932 -151.670004)
					)
				)
			)
		)
	)
)
